# T6G (Grand Teton) — schematic netlist excerpt (pin names and nets, part order shuffled) for the footprints in the layout excerpt that follows; sources: Cadence DE-HDL packaged netlist, KiCad conversion of 04192023_DAF0TMB3IC0_F0TG_MB_C_brd_V02_OCP.brd

R4270  Q_RES  2.2K 5% EMPTY  pkg 0402LF  page 252 : A = P3V3_AUX ; B = SMB_VR_SENSOR_3V3AUX_SDA
R3600  Q_RES  0 5% CHIP  pkg 0402LF  page 236 : A = SMB_INA230_1_3V3AUX_SCL_R ; B = SMB_INA230_1_3V3AUX_SCL_R1
C937  Q_CAP_DIFFBUS  DIFF BUS_0.22UF 6.3V 20% X6S  pkg C0201  page 63 : \1\ = P5E_CPU0_P1_TX_C_DP<14> ; \2\ = P5E_CPU0_P1_TX_DP<14>

(kicad_pcb
	(version 20260206)
	(generator "pcbnew")
	(generator_version "10.0")
	(general
		(thickness 1.6)
		(legacy_teardrops no)
	)
	(paper "A4")
	(title_block
		(title "04192023_DAF0TMB3IC0_F0TG_MB_C_brd_V02_OCP.brd")
		(comment 1 "Grand Teton / footprints 1994-1996 of 8354")
	)
	(layers
		(0 "F.Cu" signal "TOP")
		(4 "In1.Cu" signal "GND")
		(6 "In2.Cu" signal "IN1")
		(8 "In3.Cu" signal "GND1")
		(10 "In4.Cu" signal "IN2")
		(12 "In5.Cu" signal "GND2")
		(14 "In6.Cu" signal "IN3")
		(16 "In7.Cu" signal "GND3")
		(18 "In8.Cu" signal "VCC")
		(20 "In9.Cu" signal "VCC1")
		(22 "In10.Cu" signal "GND4")
		(24 "In11.Cu" signal "IN4")
		(26 "In12.Cu" signal "GND5")
		(28 "In13.Cu" signal "IN5")
		(30 "In14.Cu" signal "GND6")
		(32 "In15.Cu" signal "IN6")
		(34 "In16.Cu" signal "GND7")
		(2 "B.Cu" signal "BOTTOM")
		(9 "F.Adhes" user "F.Adhesive")
		(11 "B.Adhes" user "B.Adhesive")
		(13 "F.Paste" user "Package Geometry/Pastemask Top")
		(15 "B.Paste" user "Package Geometry/Pastemask Bottom")
		(5 "F.SilkS" user "Ref Des/Silkscreen Top")
		(7 "B.SilkS" user "Ref Des/Silkscreen Bottom")
		(1 "F.Mask" user "Board Geometry/Soldermask Top")
		(3 "B.Mask" user "Board Geometry/Soldermask Bottom")
		(17 "Dwgs.User" user "User.Drawings")
		(19 "Cmts.User" user "User.Comments")
		(21 "Eco1.User" user "User.Eco1")
		(23 "Eco2.User" user "User.Eco2")
		(25 "Edge.Cuts" user "Board Geometry/Outline")
		(27 "Margin" user)
		(31 "F.CrtYd" user "Package Geometry/Place Bound Top")
		(29 "B.CrtYd" user "Package Geometry/Place Bound Bottom")
		(35 "F.Fab" user "Ref Des/Assembly Top")
		(33 "B.Fab" user "Ref Des/Assembly Bottom")
	)
	(footprint ""
		(layer "F.Cu")
		(at 273.35734 -123.896628 180)
		(property "Reference" "R4270"
			(at 0 0 180)
			(layer "F.SilkS")
			(hide yes)
			(effects
				(font
					(size 1.27 1.27)
				)
			)
		)
		(property "Value" ""
			(at 0 0 180)
			(layer "F.Fab")
			(effects
				(font
					(size 1.27 1.27)
				)
			)
		)
		(duplicate_pad_numbers_are_jumpers no)
		(fp_line
			(start 0.7874 0.4064)
			(end -0.7874 0.4064)
			(stroke
				(width 0.1524)
				(type default)
			)
			(layer "F.SilkS")
		)
		(fp_line
			(start 0.7874 -0.4064)
			(end 0.7874 0.4064)
			(stroke
				(width 0.1524)
				(type default)
			)
			(layer "F.SilkS")
		)
		(fp_line
			(start -0.7874 0.4064)
			(end -0.7874 -0.4064)
			(stroke
				(width 0.1524)
				(type default)
			)
			(layer "F.SilkS")
		)
		(fp_line
			(start -0.7874 -0.4064)
			(end 0.7874 -0.4064)
			(stroke
				(width 0.1524)
				(type default)
			)
			(layer "F.SilkS")
		)
		(fp_line
			(start 0.67945 0.3048)
			(end 0.120396 0.3048)
			(stroke
				(width 0.1)
				(type default)
			)
			(layer "F.Fab")
		)
		(fp_line
			(start 0.67945 -0.3048)
			(end 0.67945 0.3048)
			(stroke
				(width 0.1)
				(type default)
			)
			(layer "F.Fab")
		)
		(fp_line
			(start 0.12065 -0.2794)
			(end 0.12065 -0.3048)
			(stroke
				(width 0.1)
				(type default)
			)
			(layer "F.Fab")
		)
		(fp_line
			(start 0.12065 -0.3048)
			(end 0.67945 -0.3048)
			(stroke
				(width 0.1)
				(type default)
			)
			(layer "F.Fab")
		)
		(fp_line
			(start 0.120396 0.3048)
			(end 0.120396 0.2794)
			(stroke
				(width 0.1)
				(type default)
			)
			(layer "F.Fab")
		)
		(fp_line
			(start 0.120396 0.2794)
			(end -0.12065 0.2794)
			(stroke
				(width 0.1)
				(type default)
			)
			(layer "F.Fab")
		)
		(fp_line
			(start -0.12065 0.3048)
			(end -0.67945 0.3048)
			(stroke
				(width 0.1)
				(type default)
			)
			(layer "F.Fab")
		)
		(fp_line
			(start -0.12065 0.2794)
			(end -0.12065 0.3048)
			(stroke
				(width 0.1)
				(type default)
			)
			(layer "F.Fab")
		)
		(fp_line
			(start -0.12065 -0.2794)
			(end 0.12065 -0.2794)
			(stroke
				(width 0.1)
				(type default)
			)
			(layer "F.Fab")
		)
		(fp_line
			(start -0.12065 -0.305054)
			(end -0.12065 -0.2794)
			(stroke
				(width 0.1)
				(type default)
			)
			(layer "F.Fab")
		)
		(fp_line
			(start -0.67945 0.3048)
			(end -0.67945 -0.305054)
			(stroke
				(width 0.1)
				(type default)
			)
			(layer "F.Fab")
		)
		(fp_line
			(start -0.67945 -0.305054)
			(end -0.12065 -0.305054)
			(stroke
				(width 0.1)
				(type default)
			)
			(layer "F.Fab")
		)
		(pad "1" smd circle
			(at -0.40005 0 180)
			(size 0 0)
			(layers "F.Cu" "F.Mask" "F.Paste")
			(net "P3V3_AUX")
		)
		(pad "2" smd circle
			(at 0.40005 0 180)
			(size 0 0)
			(layers "F.Cu" "F.Mask" "F.Paste")
			(net "SMB_VR_SENSOR_3V3AUX_SDA")
		)
	)
	(footprint ""
		(layer "F.Cu")
		(at 445.19088 -97.269808 180)
		(property "Reference" "R3600"
			(at 0 0 180)
			(layer "F.SilkS")
			(hide yes)
			(effects
				(font
					(size 1.27 1.27)
				)
			)
		)
		(property "Value" ""
			(at 0 0 180)
			(layer "F.Fab")
			(effects
				(font
					(size 1.27 1.27)
				)
			)
		)
		(duplicate_pad_numbers_are_jumpers no)
		(fp_line
			(start 0.7874 0.4064)
			(end -0.7874 0.4064)
			(stroke
				(width 0.1524)
				(type default)
			)
			(layer "F.SilkS")
		)
		(fp_line
			(start 0.7874 -0.4064)
			(end 0.7874 0.4064)
			(stroke
				(width 0.1524)
				(type default)
			)
			(layer "F.SilkS")
		)
		(fp_line
			(start -0.7874 0.4064)
			(end -0.7874 -0.4064)
			(stroke
				(width 0.1524)
				(type default)
			)
			(layer "F.SilkS")
		)
		(fp_line
			(start -0.7874 -0.4064)
			(end 0.7874 -0.4064)
			(stroke
				(width 0.1524)
				(type default)
			)
			(layer "F.SilkS")
		)
		(fp_line
			(start 0.67945 0.3048)
			(end 0.120396 0.3048)
			(stroke
				(width 0.1)
				(type default)
			)
			(layer "F.Fab")
		)
		(fp_line
			(start 0.67945 -0.3048)
			(end 0.67945 0.3048)
			(stroke
				(width 0.1)
				(type default)
			)
			(layer "F.Fab")
		)
		(fp_line
			(start 0.12065 -0.2794)
			(end 0.12065 -0.3048)
			(stroke
				(width 0.1)
				(type default)
			)
			(layer "F.Fab")
		)
		(fp_line
			(start 0.12065 -0.3048)
			(end 0.67945 -0.3048)
			(stroke
				(width 0.1)
				(type default)
			)
			(layer "F.Fab")
		)
		(fp_line
			(start 0.120396 0.3048)
			(end 0.120396 0.2794)
			(stroke
				(width 0.1)
				(type default)
			)
			(layer "F.Fab")
		)
		(fp_line
			(start 0.120396 0.2794)
			(end -0.12065 0.2794)
			(stroke
				(width 0.1)
				(type default)
			)
			(layer "F.Fab")
		)
		(fp_line
			(start -0.12065 0.3048)
			(end -0.67945 0.3048)
			(stroke
				(width 0.1)
				(type default)
			)
			(layer "F.Fab")
		)
		(fp_line
			(start -0.12065 0.2794)
			(end -0.12065 0.3048)
			(stroke
				(width 0.1)
				(type default)
			)
			(layer "F.Fab")
		)
		(fp_line
			(start -0.12065 -0.2794)
			(end 0.12065 -0.2794)
			(stroke
				(width 0.1)
				(type default)
			)
			(layer "F.Fab")
		)
		(fp_line
			(start -0.12065 -0.305054)
			(end -0.12065 -0.2794)
			(stroke
				(width 0.1)
				(type default)
			)
			(layer "F.Fab")
		)
		(fp_line
			(start -0.67945 0.3048)
			(end -0.67945 -0.305054)
			(stroke
				(width 0.1)
				(type default)
			)
			(layer "F.Fab")
		)
		(fp_line
			(start -0.67945 -0.305054)
			(end -0.12065 -0.305054)
			(stroke
				(width 0.1)
				(type default)
			)
			(layer "F.Fab")
		)
		(pad "1" smd circle
			(at -0.40005 0 180)
			(size 0 0)
			(layers "F.Cu" "F.Mask" "F.Paste")
			(net "SMB_INA230_1_3V3AUX_SCL_R")
		)
		(pad "2" smd circle
			(at 0.40005 0 180)
			(size 0 0)
			(layers "F.Cu" "F.Mask" "F.Paste")
			(net "SMB_INA230_1_3V3AUX_SCL_R1")
		)
	)
	(footprint ""
		(layer "F.Cu")
		(at 358.268524 -385.364228)
		(property "Reference" "C937"
			(at 0 0 0)
			(layer "F.SilkS")
			(hide yes)
			(effects
				(font
					(size 1.27 1.27)
				)
			)
		)
		(property "Value" ""
			(at 0 0 0)
			(layer "F.Fab")
			(effects
				(font
					(size 1.27 1.27)
				)
			)
		)
		(duplicate_pad_numbers_are_jumpers no)
		(fp_line
			(start -0.299974 -0.150114)
			(end 0.299974 -0.150114)
			(stroke
				(width 0.1)
				(type default)
			)
			(layer "F.Fab")
		)
		(fp_line
			(start -0.299974 0.150114)
			(end -0.299974 -0.150114)
			(stroke
				(width 0.1)
				(type default)
			)
			(layer "F.Fab")
		)
		(fp_line
			(start 0.299974 -0.150114)
			(end 0.299974 0.150114)
			(stroke
				(width 0.1)
				(type default)
			)
			(layer "F.Fab")
		)
		(fp_line
			(start 0.299974 0.150114)
			(end -0.299974 0.150114)
			(stroke
				(width 0.1)
				(type default)
			)
			(layer "F.Fab")
		)
		(pad "1" smd rect
			(at -0.2667 0)
			(size 0.3048 0.381)
			(layers "F.Cu" "F.Mask" "F.Paste")
			(net "P5E_CPU0_P1_TX_C_DP<14>")
		)
		(pad "2" smd rect
			(at 0.2667 0)
			(size 0.3048 0.381)
			(layers "F.Cu" "F.Mask" "F.Paste")
			(net "P5E_CPU0_P1_TX_DP<14>")
		)
	)
)
